(kicad_pcb
	(version 20260206)
	(generator "pcbnew")
	(generator_version "10.0")
	(general
		(thickness 1.6)
		(legacy_teardrops no)
	)
	(paper "A4")
	(title_block
		(title "01162023_DA0F0TEBIF0_F0T_Expander_BD_F_brd_V02_OCP.brd")
		(comment 1 "Grand Teton / footprints 2535-2540 of 9728")
	)
	(layers
		(0 "F.Cu" signal "TOP")
		(4 "In1.Cu" signal "GND")
		(6 "In2.Cu" signal "VCC")
		(8 "In3.Cu" signal "VCC1")
		(10 "In4.Cu" signal "GND1")
		(12 "In5.Cu" signal "IN1")
		(14 "In6.Cu" signal "GND2")
		(16 "In7.Cu" signal "IN2")
		(18 "In8.Cu" signal "GND3")
		(20 "In9.Cu" signal "IN3")
		(22 "In10.Cu" signal "GND4")
		(24 "In11.Cu" signal "IN4")
		(26 "In12.Cu" signal "GND5")
		(28 "In13.Cu" signal "IN5")
		(30 "In14.Cu" signal "GND6")
		(32 "In15.Cu" signal "IN6")
		(34 "In16.Cu" signal "GND7")
		(2 "B.Cu" signal "BOTTOM")
		(9 "F.Adhes" user "F.Adhesive")
		(11 "B.Adhes" user "B.Adhesive")
		(13 "F.Paste" user "Package Geometry/Pastemask Top")
		(15 "B.Paste" user "Package Geometry/Pastemask Bottom")
		(5 "F.SilkS" user "Ref Des/Silkscreen Top")
		(7 "B.SilkS" user "Ref Des/Silkscreen Bottom")
		(1 "F.Mask" user "Board Geometry/Soldermask Top")
		(3 "B.Mask" user "Board Geometry/Soldermask Bottom")
		(17 "Dwgs.User" user "User.Drawings")
		(19 "Cmts.User" user "User.Comments")
		(21 "Eco1.User" user "User.Eco1")
		(23 "Eco2.User" user "User.Eco2")
		(25 "Edge.Cuts" user "Board Geometry/Outline")
		(27 "Margin" user)
		(31 "F.CrtYd" user "Package Geometry/Place Bound Top")
		(29 "B.CrtYd" user "Package Geometry/Place Bound Bottom")
		(35 "F.Fab" user "Ref Des/Assembly Top")
		(33 "B.Fab" user "Ref Des/Assembly Bottom")
	)
	(footprint ""
		(layer "F.Cu")
		(at 244.023642 -309.211218 90)
		(property "Reference" "PR178"
			(at 0 0 90)
			(layer "F.SilkS")
			(hide yes)
			(effects
				(font
					(size 1.27 1.27)
				)
			)
		)
		(property "Value" ""
			(at 0 0 90)
			(layer "F.Fab")
			(effects
				(font
					(size 1.27 1.27)
				)
			)
		)
		(duplicate_pad_numbers_are_jumpers no)
		(fp_line
			(start 0.7874 -0.4064)
			(end 0.7874 0.4064)
			(stroke
				(width 0.1524)
				(type default)
			)
			(layer "F.SilkS")
		)
		(fp_line
			(start -0.7874 -0.4064)
			(end 0.7874 -0.4064)
			(stroke
				(width 0.1524)
				(type default)
			)
			(layer "F.SilkS")
		)
		(fp_line
			(start 0.7874 0.4064)
			(end -0.7874 0.4064)
			(stroke
				(width 0.1524)
				(type default)
			)
			(layer "F.SilkS")
		)
		(fp_line
			(start -0.7874 0.4064)
			(end -0.7874 -0.4064)
			(stroke
				(width 0.1524)
				(type default)
			)
			(layer "F.SilkS")
		)
		(fp_line
			(start -0.12065 -0.305054)
			(end -0.12065 -0.2794)
			(stroke
				(width 0.1)
				(type default)
			)
			(layer "F.Fab")
		)
		(fp_line
			(start -0.67945 -0.305054)
			(end -0.12065 -0.305054)
			(stroke
				(width 0.1)
				(type default)
			)
			(layer "F.Fab")
		)
		(fp_line
			(start 0.67945 -0.3048)
			(end 0.67945 0.3048)
			(stroke
				(width 0.1)
				(type default)
			)
			(layer "F.Fab")
		)
		(fp_line
			(start 0.12065 -0.3048)
			(end 0.67945 -0.3048)
			(stroke
				(width 0.1)
				(type default)
			)
			(layer "F.Fab")
		)
		(fp_line
			(start 0.12065 -0.2794)
			(end 0.12065 -0.3048)
			(stroke
				(width 0.1)
				(type default)
			)
			(layer "F.Fab")
		)
		(fp_line
			(start -0.12065 -0.2794)
			(end 0.12065 -0.2794)
			(stroke
				(width 0.1)
				(type default)
			)
			(layer "F.Fab")
		)
		(fp_line
			(start 0.120396 0.2794)
			(end -0.12065 0.2794)
			(stroke
				(width 0.1)
				(type default)
			)
			(layer "F.Fab")
		)
		(fp_line
			(start -0.12065 0.2794)
			(end -0.12065 0.3048)
			(stroke
				(width 0.1)
				(type default)
			)
			(layer "F.Fab")
		)
		(fp_line
			(start 0.67945 0.3048)
			(end 0.120396 0.3048)
			(stroke
				(width 0.1)
				(type default)
			)
			(layer "F.Fab")
		)
		(fp_line
			(start 0.120396 0.3048)
			(end 0.120396 0.2794)
			(stroke
				(width 0.1)
				(type default)
			)
			(layer "F.Fab")
		)
		(fp_line
			(start -0.12065 0.3048)
			(end -0.67945 0.3048)
			(stroke
				(width 0.1)
				(type default)
			)
			(layer "F.Fab")
		)
		(fp_line
			(start -0.67945 0.3048)
			(end -0.67945 -0.305054)
			(stroke
				(width 0.1)
				(type default)
			)
			(layer "F.Fab")
		)
		(pad "1" smd circle
			(at -0.40005 0 90)
			(size 0 0)
			(layers "F.Cu" "F.Mask" "F.Paste")
			(net "SH_P1V25_PEX2_FB_N")
		)
		(pad "2" smd circle
			(at 0.40005 0 90)
			(size 0 0)
			(layers "F.Cu" "F.Mask" "F.Paste")
			(net "P1V25_PEX2_FB")
		)
	)
	(footprint ""
		(layer "F.Cu")
		(at 47.287688 -350.098614 90)
		(property "Reference" "C2178"
			(at 0 0 90)
			(layer "F.SilkS")
			(hide yes)
			(effects
				(font
					(size 1.27 1.27)
				)
			)
		)
		(property "Value" ""
			(at 0 0 90)
			(layer "F.Fab")
			(effects
				(font
					(size 1.27 1.27)
				)
			)
		)
		(duplicate_pad_numbers_are_jumpers no)
		(fp_line
			(start 0.299974 -0.150114)
			(end 0.299974 0.150114)
			(stroke
				(width 0.1)
				(type default)
			)
			(layer "F.Fab")
		)
		(fp_line
			(start -0.299974 -0.150114)
			(end 0.299974 -0.150114)
			(stroke
				(width 0.1)
				(type default)
			)
			(layer "F.Fab")
		)
		(fp_line
			(start 0.299974 0.150114)
			(end -0.299974 0.150114)
			(stroke
				(width 0.1)
				(type default)
			)
			(layer "F.Fab")
		)
		(fp_line
			(start -0.299974 0.150114)
			(end -0.299974 -0.150114)
			(stroke
				(width 0.1)
				(type default)
			)
			(layer "F.Fab")
		)
		(pad "1" smd rect
			(at -0.2667 0 90)
			(size 0.3048 0.381)
			(layers "F.Cu" "F.Mask" "F.Paste")
			(net "P5E_PEX0_STN4_TX_DP<66>")
		)
		(pad "2" smd rect
			(at 0.2667 0 90)
			(size 0.3048 0.381)
			(layers "F.Cu" "F.Mask" "F.Paste")
			(net "P5E_PEX0_STN4_TX_C_DP<66>")
		)
	)
	(footprint ""
		(layer "F.Cu")
		(at 172.626782 -53.697124 -90)
		(property "Reference" "PC522"
			(at 0 0 270)
			(layer "F.SilkS")
			(hide yes)
			(effects
				(font
					(size 1.27 1.27)
				)
			)
		)
		(property "Value" ""
			(at 0 0 270)
			(layer "F.Fab")
			(effects
				(font
					(size 1.27 1.27)
				)
			)
		)
		(duplicate_pad_numbers_are_jumpers no)
		(fp_line
			(start -0.7874 0.4064)
			(end -0.7874 -0.4064)
			(stroke
				(width 0.1524)
				(type default)
			)
			(layer "F.SilkS")
		)
		(fp_line
			(start 0.7874 0.4064)
			(end -0.7874 0.4064)
			(stroke
				(width 0.1524)
				(type default)
			)
			(layer "F.SilkS")
		)
		(fp_line
			(start -0.7874 -0.4064)
			(end 0.7874 -0.4064)
			(stroke
				(width 0.1524)
				(type default)
			)
			(layer "F.SilkS")
		)
		(fp_line
			(start 0.7874 -0.4064)
			(end 0.7874 0.4064)
			(stroke
				(width 0.1524)
				(type default)
			)
			(layer "F.SilkS")
		)
		(fp_line
			(start -0.67945 0.3048)
			(end -0.67945 -0.305054)
			(stroke
				(width 0.1)
				(type default)
			)
			(layer "F.Fab")
		)
		(fp_line
			(start -0.12065 0.3048)
			(end -0.67945 0.3048)
			(stroke
				(width 0.1)
				(type default)
			)
			(layer "F.Fab")
		)
		(fp_line
			(start 0.120396 0.3048)
			(end 0.120396 0.2794)
			(stroke
				(width 0.1)
				(type default)
			)
			(layer "F.Fab")
		)
		(fp_line
			(start 0.67945 0.3048)
			(end 0.120396 0.3048)
			(stroke
				(width 0.1)
				(type default)
			)
			(layer "F.Fab")
		)
		(fp_line
			(start -0.12065 0.2794)
			(end -0.12065 0.3048)
			(stroke
				(width 0.1)
				(type default)
			)
			(layer "F.Fab")
		)
		(fp_line
			(start 0.120396 0.2794)
			(end -0.12065 0.2794)
			(stroke
				(width 0.1)
				(type default)
			)
			(layer "F.Fab")
		)
		(fp_line
			(start -0.12065 -0.2794)
			(end 0.12065 -0.2794)
			(stroke
				(width 0.1)
				(type default)
			)
			(layer "F.Fab")
		)
		(fp_line
			(start 0.12065 -0.2794)
			(end 0.12065 -0.3048)
			(stroke
				(width 0.1)
				(type default)
			)
			(layer "F.Fab")
		)
		(fp_line
			(start 0.12065 -0.3048)
			(end 0.67945 -0.3048)
			(stroke
				(width 0.1)
				(type default)
			)
			(layer "F.Fab")
		)
		(fp_line
			(start 0.67945 -0.3048)
			(end 0.67945 0.3048)
			(stroke
				(width 0.1)
				(type default)
			)
			(layer "F.Fab")
		)
		(fp_line
			(start -0.67945 -0.305054)
			(end -0.12065 -0.305054)
			(stroke
				(width 0.1)
				(type default)
			)
			(layer "F.Fab")
		)
		(fp_line
			(start -0.12065 -0.305054)
			(end -0.12065 -0.2794)
			(stroke
				(width 0.1)
				(type default)
			)
			(layer "F.Fab")
		)
		(pad "1" smd circle
			(at -0.40005 0 270)
			(size 0 0)
			(layers "F.Cu" "F.Mask" "F.Paste")
			(net "P3V3_AUX")
		)
		(pad "2" smd circle
			(at 0.40005 0 270)
			(size 0 0)
			(layers "F.Cu" "F.Mask" "F.Paste")
			(net "GND")
		)
	)
	(footprint ""
		(layer "F.Cu")
		(at 245.931182 -125.144784 180)
		(property "Reference" "PU47"
			(at 2.516632 -2.944876 0)
			(unlocked yes)
			(layer "F.SilkS")
			(effects
				(font
					(size 0.7874 0.5842)
					(thickness 0.1524)
				)
				(justify left)
			)
		)
		(property "Value" ""
			(at 0 0 180)
			(layer "F.Fab")
			(effects
				(font
					(size 1.27 1.27)
				)
			)
		)
		(duplicate_pad_numbers_are_jumpers no)
		(fp_line
			(start 1.943608 1.549908)
			(end -1.943608 1.549908)
			(stroke
				(width 0.1524)
				(type default)
			)
			(layer "F.SilkS")
		)
		(fp_line
			(start 1.943608 -1.549908)
			(end 1.943608 1.549908)
			(stroke
				(width 0.1524)
				(type default)
			)
			(layer "F.SilkS")
		)
		(fp_line
			(start -1.943608 1.549908)
			(end -1.943608 -1.549908)
			(stroke
				(width 0.1524)
				(type default)
			)
			(layer "F.SilkS")
		)
		(fp_line
			(start -1.943608 -1.549908)
			(end 1.943608 -1.549908)
			(stroke
				(width 0.1524)
				(type default)
			)
			(layer "F.SilkS")
		)
		(fp_poly
			(pts
				(xy -2.019808 -1.549908) (xy -1.257808 -1.549908) (xy -1.257808 -1.880108) (xy -2.019808 -1.880108)
			)
			(stroke
				(width 0)
				(type default)
			)
			(fill yes)
			(layer "F.SilkS")
		)
		(fp_line
			(start 1.549908 1.549908)
			(end -1.549908 1.549908)
			(stroke
				(width 0.1)
				(type default)
			)
			(layer "F.Fab")
		)
		(fp_line
			(start 1.549908 -1.549908)
			(end 1.549908 1.549908)
			(stroke
				(width 0.1)
				(type default)
			)
			(layer "F.Fab")
		)
		(fp_line
			(start -1.549908 1.549908)
			(end -1.549908 -1.549908)
			(stroke
				(width 0.1)
				(type default)
			)
			(layer "F.Fab")
		)
		(fp_line
			(start -1.549908 -1.549908)
			(end 1.549908 -1.549908)
			(stroke
				(width 0.1)
				(type default)
			)
			(layer "F.Fab")
		)
		(fp_poly
			(pts
				(xy -2.019808 -1.549908) (xy -1.257808 -1.549908) (xy -1.257808 -1.880108) (xy -2.019808 -1.880108)
			)
			(stroke
				(width 0)
				(type default)
			)
			(fill yes)
			(layer "F.Fab")
		)
		(pad "1" smd rect
			(at -1.500124 -1.249934 90)
			(size 0.2794 0.6096)
			(layers "F.Cu" "F.Mask" "F.Paste")
			(net "P3V3_NIC4")
		)
		(pad "2" smd rect
			(at -1.500124 -0.750062 90)
			(size 0.2794 0.6096)
			(layers "F.Cu" "F.Mask" "F.Paste")
			(net "P3V3_NIC4")
		)
		(pad "3" smd rect
			(at -1.500124 -0.249936 90)
			(size 0.2794 0.6096)
			(layers "F.Cu" "F.Mask" "F.Paste")
			(net "P3V3_NIC4")
		)
		(pad "4" smd rect
			(at -1.500124 0.249936 90)
			(size 0.2794 0.6096)
			(layers "F.Cu" "F.Mask" "F.Paste")
			(net "P3V3_NIC4")
		)
		(pad "5" smd rect
			(at -1.500124 0.750062 90)
			(size 0.2794 0.6096)
			(layers "F.Cu" "F.Mask" "F.Paste")
			(net "P3V3_NIC4")
		)
		(pad "6" smd rect
			(at -1.500124 1.249934 90)
			(size 0.2794 0.6096)
			(layers "F.Cu" "F.Mask" "F.Paste")
			(net "GND")
		)
		(pad "7" smd rect
			(at 1.500124 1.249934 90)
			(size 0.2794 0.6096)
			(layers "F.Cu" "F.Mask" "F.Paste")
			(net "P3V3_NIC4_SS")
		)
		(pad "8" smd rect
			(at 1.500124 0.750062 90)
			(size 0.2794 0.6096)
			(layers "F.Cu" "F.Mask" "F.Paste")
			(net "PWRGD_P3V3_NIC4")
		)
		(pad "9" smd rect
			(at 1.500124 0.249936 90)
			(size 0.2794 0.6096)
			(layers "F.Cu" "F.Mask" "F.Paste")
			(net "P3V3_NIC4_OCP")
		)
		(pad "10" smd rect
			(at 1.500124 -0.249936 90)
			(size 0.2794 0.6096)
			(layers "F.Cu" "F.Mask" "F.Paste")
			(net "P5V_AUX")
		)
		(pad "11" smd rect
			(at 1.500124 -0.750062 90)
			(size 0.2794 0.6096)
			(layers "F.Cu" "F.Mask" "F.Paste")
			(net "HP_NIC4_EN")
		)
		(pad "12" smd rect
			(at 1.500124 -1.249934 90)
			(size 0.2794 0.6096)
			(layers "F.Cu" "F.Mask" "F.Paste")
			(net "P3V3_AUX")
		)
		(pad "13" smd rect
			(at 0 0 180)
			(size 1.9812 2.7178)
			(layers "F.Cu" "F.Mask" "F.Paste")
			(net "P3V3_AUX")
		)
		(zone
			(layer "F.Cu")
			(hatch none 0.5)
			(connect_pads
				(clearance 0)
			)
			(min_thickness 0.25)
			(keepout
				(tracks not_allowed)
				(vias allowed)
				(pads allowed)
				(copperpour not_allowed)
				(footprints allowed)
			)
			(placement
				(enabled no)
				(sheetname "")
			)
			(fill
				(thermal_gap 0.5)
				(thermal_bridge_width 0.5)
				(island_removal_mode 0)
			)
			(polygon
				(pts
					(xy 244.788182 -123.595384) (xy 244.788182 -123.722384) (xy 244.788182 -126.694184) (xy 244.788182 -126.694692)
					(xy 247.074182 -126.694692) (xy 247.074182 -126.694184) (xy 247.074182 -126.567184) (xy 247.074182 -125.144784)
					(xy 246.972582 -125.144784) (xy 246.972582 -126.567184) (xy 244.889782 -126.567184) (xy 244.889782 -123.722384)
					(xy 246.972582 -123.722384) (xy 246.972582 -125.119384) (xy 247.074182 -125.119384) (xy 247.074182 -123.722384)
					(xy 247.074182 -123.595384) (xy 247.074182 -123.594876) (xy 244.788182 -123.594876)
				)
			)
		)
	)
	(footprint ""
		(layer "F.Cu")
		(at 91.883992 -289.230816 90)
		(property "Reference" "R3891"
			(at 0 0 90)
			(layer "F.SilkS")
			(hide yes)
			(effects
				(font
					(size 1.27 1.27)
				)
			)
		)
		(property "Value" ""
			(at 0 0 90)
			(layer "F.Fab")
			(effects
				(font
					(size 1.27 1.27)
				)
			)
		)
		(duplicate_pad_numbers_are_jumpers no)
		(fp_line
			(start 0.7874 -0.4064)
			(end 0.7874 0.4064)
			(stroke
				(width 0.1524)
				(type default)
			)
			(layer "F.SilkS")
		)
		(fp_line
			(start -0.7874 -0.4064)
			(end 0.7874 -0.4064)
			(stroke
				(width 0.1524)
				(type default)
			)
			(layer "F.SilkS")
		)
		(fp_line
			(start 0.7874 0.4064)
			(end -0.7874 0.4064)
			(stroke
				(width 0.1524)
				(type default)
			)
			(layer "F.SilkS")
		)
		(fp_line
			(start -0.7874 0.4064)
			(end -0.7874 -0.4064)
			(stroke
				(width 0.1524)
				(type default)
			)
			(layer "F.SilkS")
		)
		(fp_line
			(start -0.12065 -0.305054)
			(end -0.12065 -0.2794)
			(stroke
				(width 0.1)
				(type default)
			)
			(layer "F.Fab")
		)
		(fp_line
			(start -0.67945 -0.305054)
			(end -0.12065 -0.305054)
			(stroke
				(width 0.1)
				(type default)
			)
			(layer "F.Fab")
		)
		(fp_line
			(start 0.67945 -0.3048)
			(end 0.67945 0.3048)
			(stroke
				(width 0.1)
				(type default)
			)
			(layer "F.Fab")
		)
		(fp_line
			(start 0.12065 -0.3048)
			(end 0.67945 -0.3048)
			(stroke
				(width 0.1)
				(type default)
			)
			(layer "F.Fab")
		)
		(fp_line
			(start 0.12065 -0.2794)
			(end 0.12065 -0.3048)
			(stroke
				(width 0.1)
				(type default)
			)
			(layer "F.Fab")
		)
		(fp_line
			(start -0.12065 -0.2794)
			(end 0.12065 -0.2794)
			(stroke
				(width 0.1)
				(type default)
			)
			(layer "F.Fab")
		)
		(fp_line
			(start 0.120396 0.2794)
			(end -0.12065 0.2794)
			(stroke
				(width 0.1)
				(type default)
			)
			(layer "F.Fab")
		)
		(fp_line
			(start -0.12065 0.2794)
			(end -0.12065 0.3048)
			(stroke
				(width 0.1)
				(type default)
			)
			(layer "F.Fab")
		)
		(fp_line
			(start 0.67945 0.3048)
			(end 0.120396 0.3048)
			(stroke
				(width 0.1)
				(type default)
			)
			(layer "F.Fab")
		)
		(fp_line
			(start 0.120396 0.3048)
			(end 0.120396 0.2794)
			(stroke
				(width 0.1)
				(type default)
			)
			(layer "F.Fab")
		)
		(fp_line
			(start -0.12065 0.3048)
			(end -0.67945 0.3048)
			(stroke
				(width 0.1)
				(type default)
			)
			(layer "F.Fab")
		)
		(fp_line
			(start -0.67945 0.3048)
			(end -0.67945 -0.305054)
			(stroke
				(width 0.1)
				(type default)
			)
			(layer "F.Fab")
		)
		(pad "1" smd circle
			(at -0.40005 0 90)
			(size 0 0)
			(layers "F.Cu" "F.Mask" "F.Paste")
			(net "SMB_PEX0_FPGA_SCL")
		)
		(pad "2" smd circle
			(at 0.40005 0 90)
			(size 0 0)
			(layers "F.Cu" "F.Mask" "F.Paste")
			(net "SMB_PEX0_HOST_LS_SCL")
		)
	)
	(footprint ""
		(layer "F.Cu")
		(at 72.672956 -22.867366 90)
		(property "Reference" "C3886"
			(at 0 0 90)
			(layer "F.SilkS")
			(hide yes)
			(effects
				(font
					(size 1.27 1.27)
				)
			)
		)
		(property "Value" ""
			(at 0 0 90)
			(layer "F.Fab")
			(effects
				(font
					(size 1.27 1.27)
				)
			)
		)
		(duplicate_pad_numbers_are_jumpers no)
		(fp_line
			(start 0.7874 -0.4064)
			(end 0.7874 0.4064)
			(stroke
				(width 0.1524)
				(type default)
			)
			(layer "F.SilkS")
		)
		(fp_line
			(start -0.7874 -0.4064)
			(end 0.7874 -0.4064)
			(stroke
				(width 0.1524)
				(type default)
			)
			(layer "F.SilkS")
		)
		(fp_line
			(start 0.7874 0.4064)
			(end -0.7874 0.4064)
			(stroke
				(width 0.1524)
				(type default)
			)
			(layer "F.SilkS")
		)
		(fp_line
			(start -0.7874 0.4064)
			(end -0.7874 -0.4064)
			(stroke
				(width 0.1524)
				(type default)
			)
			(layer "F.SilkS")
		)
		(fp_line
			(start -0.12065 -0.305054)
			(end -0.12065 -0.2794)
			(stroke
				(width 0.1)
				(type default)
			)
			(layer "F.Fab")
		)
		(fp_line
			(start -0.67945 -0.305054)
			(end -0.12065 -0.305054)
			(stroke
				(width 0.1)
				(type default)
			)
			(layer "F.Fab")
		)
		(fp_line
			(start 0.67945 -0.3048)
			(end 0.67945 0.3048)
			(stroke
				(width 0.1)
				(type default)
			)
			(layer "F.Fab")
		)
		(fp_line
			(start 0.12065 -0.3048)
			(end 0.67945 -0.3048)
			(stroke
				(width 0.1)
				(type default)
			)
			(layer "F.Fab")
		)
		(fp_line
			(start 0.12065 -0.2794)
			(end 0.12065 -0.3048)
			(stroke
				(width 0.1)
				(type default)
			)
			(layer "F.Fab")
		)
		(fp_line
			(start -0.12065 -0.2794)
			(end 0.12065 -0.2794)
			(stroke
				(width 0.1)
				(type default)
			)
			(layer "F.Fab")
		)
		(fp_line
			(start 0.120396 0.2794)
			(end -0.12065 0.2794)
			(stroke
				(width 0.1)
				(type default)
			)
			(layer "F.Fab")
		)
		(fp_line
			(start -0.12065 0.2794)
			(end -0.12065 0.3048)
			(stroke
				(width 0.1)
				(type default)
			)
			(layer "F.Fab")
		)
		(fp_line
			(start 0.67945 0.3048)
			(end 0.120396 0.3048)
			(stroke
				(width 0.1)
				(type default)
			)
			(layer "F.Fab")
		)
		(fp_line
			(start 0.120396 0.3048)
			(end 0.120396 0.2794)
			(stroke
				(width 0.1)
				(type default)
			)
			(layer "F.Fab")
		)
		(fp_line
			(start -0.12065 0.3048)
			(end -0.67945 0.3048)
			(stroke
				(width 0.1)
				(type default)
			)
			(layer "F.Fab")
		)
		(fp_line
			(start -0.67945 0.3048)
			(end -0.67945 -0.305054)
			(stroke
				(width 0.1)
				(type default)
			)
			(layer "F.Fab")
		)
		(pad "1" smd circle
			(at -0.40005 0 90)
			(size 0 0)
			(layers "F.Cu" "F.Mask" "F.Paste")
			(net "P12V_SSD2")
		)
		(pad "2" smd circle
			(at 0.40005 0 90)
			(size 0 0)
			(layers "F.Cu" "F.Mask" "F.Paste")
			(net "GND")
		)
	)
)
